(kicad_pcb
	(version 20260206)
	(generator "pcbnew")
	(generator_version "10.0")
	(general
		(thickness 1.6)
		(legacy_teardrops no)
	)
	(paper "A4")
	(title_block
		(title "01162023_DA0F0TEBIF0_F0T_Expander_BD_F_brd_V02_OCP.brd")
		(comment 1 "Grand Teton / footprints 9041-9052 of 9728")
	)
	(layers
		(0 "F.Cu" signal "TOP")
		(4 "In1.Cu" signal "GND")
		(6 "In2.Cu" signal "VCC")
		(8 "In3.Cu" signal "VCC1")
		(10 "In4.Cu" signal "GND1")
		(12 "In5.Cu" signal "IN1")
		(14 "In6.Cu" signal "GND2")
		(16 "In7.Cu" signal "IN2")
		(18 "In8.Cu" signal "GND3")
		(20 "In9.Cu" signal "IN3")
		(22 "In10.Cu" signal "GND4")
		(24 "In11.Cu" signal "IN4")
		(26 "In12.Cu" signal "GND5")
		(28 "In13.Cu" signal "IN5")
		(30 "In14.Cu" signal "GND6")
		(32 "In15.Cu" signal "IN6")
		(34 "In16.Cu" signal "GND7")
		(2 "B.Cu" signal "BOTTOM")
		(9 "F.Adhes" user "F.Adhesive")
		(11 "B.Adhes" user "B.Adhesive")
		(13 "F.Paste" user "Package Geometry/Pastemask Top")
		(15 "B.Paste" user "Package Geometry/Pastemask Bottom")
		(5 "F.SilkS" user "Ref Des/Silkscreen Top")
		(7 "B.SilkS" user "Ref Des/Silkscreen Bottom")
		(1 "F.Mask" user "Board Geometry/Soldermask Top")
		(3 "B.Mask" user "Board Geometry/Soldermask Bottom")
		(17 "Dwgs.User" user "User.Drawings")
		(19 "Cmts.User" user "User.Comments")
		(21 "Eco1.User" user "User.Eco1")
		(23 "Eco2.User" user "User.Eco2")
		(25 "Edge.Cuts" user "Board Geometry/Outline")
		(27 "Margin" user)
		(31 "F.CrtYd" user "Package Geometry/Place Bound Top")
		(29 "B.CrtYd" user "Package Geometry/Place Bound Bottom")
		(35 "F.Fab" user "Ref Des/Assembly Top")
		(33 "B.Fab" user "Ref Des/Assembly Bottom")
	)
	(footprint ""
		(layer "B.Cu")
		(at 340.868 -207.772 90)
		(property "Reference" "R4136"
			(at 0 0 90)
			(layer "B.SilkS")
			(hide yes)
			(effects
				(font
					(size 1.27 1.27)
				)
				(justify mirror)
			)
		)
		(property "Value" ""
			(at 0 0 90)
			(layer "B.Fab")
			(effects
				(font
					(size 1.27 1.27)
				)
				(justify mirror)
			)
		)
		(duplicate_pad_numbers_are_jumpers no)
		(fp_line
			(start 0.7874 -0.4064)
			(end -0.7874 -0.4064)
			(stroke
				(width 0.1524)
				(type default)
			)
			(layer "B.SilkS")
		)
		(fp_line
			(start -0.7874 -0.4064)
			(end -0.7874 0.4064)
			(stroke
				(width 0.1524)
				(type default)
			)
			(layer "B.SilkS")
		)
		(fp_line
			(start 0.7874 0.4064)
			(end 0.7874 -0.4064)
			(stroke
				(width 0.1524)
				(type default)
			)
			(layer "B.SilkS")
		)
		(fp_line
			(start -0.7874 0.4064)
			(end 0.7874 0.4064)
			(stroke
				(width 0.1524)
				(type default)
			)
			(layer "B.SilkS")
		)
		(fp_line
			(start 0.67945 -0.305054)
			(end 0.12065 -0.305054)
			(stroke
				(width 0.1)
				(type default)
			)
			(layer "B.Fab")
		)
		(fp_line
			(start 0.12065 -0.305054)
			(end 0.12065 -0.2794)
			(stroke
				(width 0.1)
				(type default)
			)
			(layer "B.Fab")
		)
		(fp_line
			(start -0.12065 -0.3048)
			(end -0.67945 -0.3048)
			(stroke
				(width 0.1)
				(type default)
			)
			(layer "B.Fab")
		)
		(fp_line
			(start -0.67945 -0.3048)
			(end -0.67945 0.3048)
			(stroke
				(width 0.1)
				(type default)
			)
			(layer "B.Fab")
		)
		(fp_line
			(start 0.12065 -0.2794)
			(end -0.12065 -0.2794)
			(stroke
				(width 0.1)
				(type default)
			)
			(layer "B.Fab")
		)
		(fp_line
			(start -0.12065 -0.2794)
			(end -0.12065 -0.3048)
			(stroke
				(width 0.1)
				(type default)
			)
			(layer "B.Fab")
		)
		(fp_line
			(start 0.12065 0.2794)
			(end 0.12065 0.3048)
			(stroke
				(width 0.1)
				(type default)
			)
			(layer "B.Fab")
		)
		(fp_line
			(start -0.120396 0.2794)
			(end 0.12065 0.2794)
			(stroke
				(width 0.1)
				(type default)
			)
			(layer "B.Fab")
		)
		(fp_line
			(start 0.67945 0.3048)
			(end 0.67945 -0.305054)
			(stroke
				(width 0.1)
				(type default)
			)
			(layer "B.Fab")
		)
		(fp_line
			(start 0.12065 0.3048)
			(end 0.67945 0.3048)
			(stroke
				(width 0.1)
				(type default)
			)
			(layer "B.Fab")
		)
		(fp_line
			(start -0.120396 0.3048)
			(end -0.120396 0.2794)
			(stroke
				(width 0.1)
				(type default)
			)
			(layer "B.Fab")
		)
		(fp_line
			(start -0.67945 0.3048)
			(end -0.120396 0.3048)
			(stroke
				(width 0.1)
				(type default)
			)
			(layer "B.Fab")
		)
		(pad "1" smd circle
			(at 0.40005 0 270)
			(size 0 0)
			(layers "B.Cu" "B.Mask" "B.Paste")
			(net "SSD13_PWRDIS")
		)
		(pad "2" smd circle
			(at -0.40005 0 270)
			(size 0 0)
			(layers "B.Cu" "B.Mask" "B.Paste")
			(net "SSD13_PWRDIS_R")
		)
	)
	(footprint ""
		(layer "B.Cu")
		(at 290.44011 -297.79976 -90)
		(property "Reference" "C1643"
			(at 0 0 90)
			(layer "B.SilkS")
			(hide yes)
			(effects
				(font
					(size 1.27 1.27)
				)
				(justify mirror)
			)
		)
		(property "Value" ""
			(at 0 0 90)
			(layer "B.Fab")
			(effects
				(font
					(size 1.27 1.27)
				)
				(justify mirror)
			)
		)
		(duplicate_pad_numbers_are_jumpers no)
		(fp_line
			(start -0.299974 0.150114)
			(end 0.299974 0.150114)
			(stroke
				(width 0.1)
				(type default)
			)
			(layer "B.Fab")
		)
		(fp_line
			(start 0.299974 0.150114)
			(end 0.299974 -0.150114)
			(stroke
				(width 0.1)
				(type default)
			)
			(layer "B.Fab")
		)
		(fp_line
			(start -0.299974 -0.150114)
			(end -0.299974 0.150114)
			(stroke
				(width 0.1)
				(type default)
			)
			(layer "B.Fab")
		)
		(fp_line
			(start 0.299974 -0.150114)
			(end -0.299974 -0.150114)
			(stroke
				(width 0.1)
				(type default)
			)
			(layer "B.Fab")
		)
		(pad "1" smd rect
			(at 0.2667 0 90)
			(size 0.3048 0.381)
			(layers "B.Cu" "B.Mask" "B.Paste")
			(net "P0V8_PEX2")
		)
		(pad "2" smd rect
			(at -0.2667 0 90)
			(size 0.3048 0.381)
			(layers "B.Cu" "B.Mask" "B.Paste")
			(net "GND")
		)
	)
	(footprint ""
		(layer "B.Cu")
		(at 62.024768 -293.99992 -90)
		(property "Reference" "C1146"
			(at 0 0 90)
			(layer "B.SilkS")
			(hide yes)
			(effects
				(font
					(size 1.27 1.27)
				)
				(justify mirror)
			)
		)
		(property "Value" ""
			(at 0 0 90)
			(layer "B.Fab")
			(effects
				(font
					(size 1.27 1.27)
				)
				(justify mirror)
			)
		)
		(duplicate_pad_numbers_are_jumpers no)
		(fp_line
			(start -0.299974 0.150114)
			(end 0.299974 0.150114)
			(stroke
				(width 0.1)
				(type default)
			)
			(layer "B.Fab")
		)
		(fp_line
			(start 0.299974 0.150114)
			(end 0.299974 -0.150114)
			(stroke
				(width 0.1)
				(type default)
			)
			(layer "B.Fab")
		)
		(fp_line
			(start -0.299974 -0.150114)
			(end -0.299974 0.150114)
			(stroke
				(width 0.1)
				(type default)
			)
			(layer "B.Fab")
		)
		(fp_line
			(start 0.299974 -0.150114)
			(end -0.299974 -0.150114)
			(stroke
				(width 0.1)
				(type default)
			)
			(layer "B.Fab")
		)
		(pad "1" smd rect
			(at 0.2667 0 90)
			(size 0.3048 0.381)
			(layers "B.Cu" "B.Mask" "B.Paste")
			(net "P0V8_PEX0")
		)
		(pad "2" smd rect
			(at -0.2667 0 90)
			(size 0.3048 0.381)
			(layers "B.Cu" "B.Mask" "B.Paste")
			(net "GND")
		)
	)
	(footprint ""
		(layer "B.Cu")
		(at 282.824936 -293.99992 90)
		(property "Reference" "C1644"
			(at 0 0 90)
			(layer "B.SilkS")
			(hide yes)
			(effects
				(font
					(size 1.27 1.27)
				)
				(justify mirror)
			)
		)
		(property "Value" ""
			(at 0 0 90)
			(layer "B.Fab")
			(effects
				(font
					(size 1.27 1.27)
				)
				(justify mirror)
			)
		)
		(duplicate_pad_numbers_are_jumpers no)
		(fp_line
			(start 0.299974 -0.150114)
			(end -0.299974 -0.150114)
			(stroke
				(width 0.1)
				(type default)
			)
			(layer "B.Fab")
		)
		(fp_line
			(start -0.299974 -0.150114)
			(end -0.299974 0.150114)
			(stroke
				(width 0.1)
				(type default)
			)
			(layer "B.Fab")
		)
		(fp_line
			(start 0.299974 0.150114)
			(end 0.299974 -0.150114)
			(stroke
				(width 0.1)
				(type default)
			)
			(layer "B.Fab")
		)
		(fp_line
			(start -0.299974 0.150114)
			(end 0.299974 0.150114)
			(stroke
				(width 0.1)
				(type default)
			)
			(layer "B.Fab")
		)
		(pad "1" smd rect
			(at 0.2667 0 270)
			(size 0.3048 0.381)
			(layers "B.Cu" "B.Mask" "B.Paste")
			(net "P0V8_PEX2")
		)
		(pad "2" smd rect
			(at -0.2667 0 270)
			(size 0.3048 0.381)
			(layers "B.Cu" "B.Mask" "B.Paste")
			(net "GND")
		)
	)
	(footprint ""
		(layer "B.Cu")
		(at 392.749786 -294.94988)
		(property "Reference" "C3524"
			(at 0 0 0)
			(layer "B.SilkS")
			(hide yes)
			(effects
				(font
					(size 1.27 1.27)
				)
				(justify mirror)
			)
		)
		(property "Value" ""
			(at 0 0 0)
			(layer "B.Fab")
			(effects
				(font
					(size 1.27 1.27)
				)
				(justify mirror)
			)
		)
		(duplicate_pad_numbers_are_jumpers no)
		(fp_line
			(start -0.299974 -0.150114)
			(end -0.299974 0.150114)
			(stroke
				(width 0.1)
				(type default)
			)
			(layer "B.Fab")
		)
		(fp_line
			(start -0.299974 0.150114)
			(end 0.299974 0.150114)
			(stroke
				(width 0.1)
				(type default)
			)
			(layer "B.Fab")
		)
		(fp_line
			(start 0.299974 -0.150114)
			(end -0.299974 -0.150114)
			(stroke
				(width 0.1)
				(type default)
			)
			(layer "B.Fab")
		)
		(fp_line
			(start 0.299974 0.150114)
			(end 0.299974 -0.150114)
			(stroke
				(width 0.1)
				(type default)
			)
			(layer "B.Fab")
		)
		(pad "1" smd rect
			(at 0.2667 0 180)
			(size 0.3048 0.381)
			(layers "B.Cu" "B.Mask" "B.Paste")
			(net "P1V8_PEX")
		)
		(pad "2" smd rect
			(at -0.2667 0 180)
			(size 0.3048 0.381)
			(layers "B.Cu" "B.Mask" "B.Paste")
			(net "GND")
		)
	)
	(footprint ""
		(layer "B.Cu")
		(at 303.249838 -294.4749 180)
		(property "Reference" "C3274"
			(at 0 0 0)
			(layer "B.SilkS")
			(hide yes)
			(effects
				(font
					(size 1.27 1.27)
				)
				(justify mirror)
			)
		)
		(property "Value" ""
			(at 0 0 0)
			(layer "B.Fab")
			(effects
				(font
					(size 1.27 1.27)
				)
				(justify mirror)
			)
		)
		(duplicate_pad_numbers_are_jumpers no)
		(fp_line
			(start 0.299974 0.150114)
			(end 0.299974 -0.150114)
			(stroke
				(width 0.1)
				(type default)
			)
			(layer "B.Fab")
		)
		(fp_line
			(start 0.299974 -0.150114)
			(end -0.299974 -0.150114)
			(stroke
				(width 0.1)
				(type default)
			)
			(layer "B.Fab")
		)
		(fp_line
			(start -0.299974 0.150114)
			(end 0.299974 0.150114)
			(stroke
				(width 0.1)
				(type default)
			)
			(layer "B.Fab")
		)
		(fp_line
			(start -0.299974 -0.150114)
			(end -0.299974 0.150114)
			(stroke
				(width 0.1)
				(type default)
			)
			(layer "B.Fab")
		)
		(pad "1" smd rect
			(at 0.2667 0)
			(size 0.3048 0.381)
			(layers "B.Cu" "B.Mask" "B.Paste")
			(net "P1V25_PEX2")
		)
		(pad "2" smd rect
			(at -0.2667 0)
			(size 0.3048 0.381)
			(layers "B.Cu" "B.Mask" "B.Paste")
			(net "GND")
		)
	)
	(footprint ""
		(layer "B.Cu")
		(at 54.424834 -293.99992 90)
		(property "Reference" "C1150"
			(at 0 0 90)
			(layer "B.SilkS")
			(hide yes)
			(effects
				(font
					(size 1.27 1.27)
				)
				(justify mirror)
			)
		)
		(property "Value" ""
			(at 0 0 90)
			(layer "B.Fab")
			(effects
				(font
					(size 1.27 1.27)
				)
				(justify mirror)
			)
		)
		(duplicate_pad_numbers_are_jumpers no)
		(fp_line
			(start 0.299974 -0.150114)
			(end -0.299974 -0.150114)
			(stroke
				(width 0.1)
				(type default)
			)
			(layer "B.Fab")
		)
		(fp_line
			(start -0.299974 -0.150114)
			(end -0.299974 0.150114)
			(stroke
				(width 0.1)
				(type default)
			)
			(layer "B.Fab")
		)
		(fp_line
			(start 0.299974 0.150114)
			(end 0.299974 -0.150114)
			(stroke
				(width 0.1)
				(type default)
			)
			(layer "B.Fab")
		)
		(fp_line
			(start -0.299974 0.150114)
			(end 0.299974 0.150114)
			(stroke
				(width 0.1)
				(type default)
			)
			(layer "B.Fab")
		)
		(pad "1" smd rect
			(at 0.2667 0 270)
			(size 0.3048 0.381)
			(layers "B.Cu" "B.Mask" "B.Paste")
			(net "P0V8_PEX0")
		)
		(pad "2" smd rect
			(at -0.2667 0 270)
			(size 0.3048 0.381)
			(layers "B.Cu" "B.Mask" "B.Paste")
			(net "GND")
		)
	)
	(footprint ""
		(layer "B.Cu")
		(at 52.999894 -301.599854 -90)
		(property "Reference" "C1194"
			(at 0 0 90)
			(layer "B.SilkS")
			(hide yes)
			(effects
				(font
					(size 1.27 1.27)
				)
				(justify mirror)
			)
		)
		(property "Value" ""
			(at 0 0 90)
			(layer "B.Fab")
			(effects
				(font
					(size 1.27 1.27)
				)
				(justify mirror)
			)
		)
		(duplicate_pad_numbers_are_jumpers no)
		(fp_line
			(start -0.299974 0.150114)
			(end 0.299974 0.150114)
			(stroke
				(width 0.1)
				(type default)
			)
			(layer "B.Fab")
		)
		(fp_line
			(start 0.299974 0.150114)
			(end 0.299974 -0.150114)
			(stroke
				(width 0.1)
				(type default)
			)
			(layer "B.Fab")
		)
		(fp_line
			(start -0.299974 -0.150114)
			(end -0.299974 0.150114)
			(stroke
				(width 0.1)
				(type default)
			)
			(layer "B.Fab")
		)
		(fp_line
			(start 0.299974 -0.150114)
			(end -0.299974 -0.150114)
			(stroke
				(width 0.1)
				(type default)
			)
			(layer "B.Fab")
		)
		(pad "1" smd rect
			(at 0.2667 0 90)
			(size 0.3048 0.381)
			(layers "B.Cu" "B.Mask" "B.Paste")
			(net "P0V8_SERDES_VDDA_PEX0")
		)
		(pad "2" smd rect
			(at -0.2667 0 90)
			(size 0.3048 0.381)
			(layers "B.Cu" "B.Mask" "B.Paste")
			(net "GND")
		)
	)
	(footprint ""
		(layer "B.Cu")
		(at 295.174924 -286.399732 90)
		(property "Reference" "C3327"
			(at 0 0 90)
			(layer "B.SilkS")
			(hide yes)
			(effects
				(font
					(size 1.27 1.27)
				)
				(justify mirror)
			)
		)
		(property "Value" ""
			(at 0 0 90)
			(layer "B.Fab")
			(effects
				(font
					(size 1.27 1.27)
				)
				(justify mirror)
			)
		)
		(duplicate_pad_numbers_are_jumpers no)
		(fp_line
			(start 0.299974 -0.150114)
			(end -0.299974 -0.150114)
			(stroke
				(width 0.1)
				(type default)
			)
			(layer "B.Fab")
		)
		(fp_line
			(start -0.299974 -0.150114)
			(end -0.299974 0.150114)
			(stroke
				(width 0.1)
				(type default)
			)
			(layer "B.Fab")
		)
		(fp_line
			(start 0.299974 0.150114)
			(end 0.299974 -0.150114)
			(stroke
				(width 0.1)
				(type default)
			)
			(layer "B.Fab")
		)
		(fp_line
			(start -0.299974 0.150114)
			(end 0.299974 0.150114)
			(stroke
				(width 0.1)
				(type default)
			)
			(layer "B.Fab")
		)
		(pad "1" smd rect
			(at 0.2667 0 270)
			(size 0.3048 0.381)
			(layers "B.Cu" "B.Mask" "B.Paste")
			(net "P1V25_SERDES_VDDPLL_PEX2")
		)
		(pad "2" smd rect
			(at -0.2667 0 270)
			(size 0.3048 0.381)
			(layers "B.Cu" "B.Mask" "B.Paste")
			(net "GND")
		)
	)
	(footprint ""
		(layer "B.Cu")
		(at 278.064214 -146.148552 180)
		(property "Reference" "C909"
			(at 0 0 0)
			(layer "B.SilkS")
			(hide yes)
			(effects
				(font
					(size 1.27 1.27)
				)
				(justify mirror)
			)
		)
		(property "Value" ""
			(at 0 0 0)
			(layer "B.Fab")
			(effects
				(font
					(size 1.27 1.27)
				)
				(justify mirror)
			)
		)
		(duplicate_pad_numbers_are_jumpers no)
		(fp_line
			(start 0.299974 0.150114)
			(end 0.299974 -0.150114)
			(stroke
				(width 0.1)
				(type default)
			)
			(layer "B.Fab")
		)
		(fp_line
			(start 0.299974 -0.150114)
			(end -0.299974 -0.150114)
			(stroke
				(width 0.1)
				(type default)
			)
			(layer "B.Fab")
		)
		(fp_line
			(start -0.299974 0.150114)
			(end 0.299974 0.150114)
			(stroke
				(width 0.1)
				(type default)
			)
			(layer "B.Fab")
		)
		(fp_line
			(start -0.299974 -0.150114)
			(end -0.299974 0.150114)
			(stroke
				(width 0.1)
				(type default)
			)
			(layer "B.Fab")
		)
		(pad "1" smd rect
			(at 0.2667 0)
			(size 0.3048 0.381)
			(layers "B.Cu" "B.Mask" "B.Paste")
			(net "P12V_NIC4")
		)
		(pad "2" smd rect
			(at -0.2667 0)
			(size 0.3048 0.381)
			(layers "B.Cu" "B.Mask" "B.Paste")
			(net "GND")
		)
	)
	(footprint ""
		(layer "B.Cu")
		(at 173.850046 -303.499774 -90)
		(property "Reference" "C3091"
			(at 0 0 90)
			(layer "B.SilkS")
			(hide yes)
			(effects
				(font
					(size 1.27 1.27)
				)
				(justify mirror)
			)
		)
		(property "Value" ""
			(at 0 0 90)
			(layer "B.Fab")
			(effects
				(font
					(size 1.27 1.27)
				)
				(justify mirror)
			)
		)
		(duplicate_pad_numbers_are_jumpers no)
		(fp_line
			(start -0.299974 0.150114)
			(end 0.299974 0.150114)
			(stroke
				(width 0.1)
				(type default)
			)
			(layer "B.Fab")
		)
		(fp_line
			(start 0.299974 0.150114)
			(end 0.299974 -0.150114)
			(stroke
				(width 0.1)
				(type default)
			)
			(layer "B.Fab")
		)
		(fp_line
			(start -0.299974 -0.150114)
			(end -0.299974 0.150114)
			(stroke
				(width 0.1)
				(type default)
			)
			(layer "B.Fab")
		)
		(fp_line
			(start 0.299974 -0.150114)
			(end -0.299974 -0.150114)
			(stroke
				(width 0.1)
				(type default)
			)
			(layer "B.Fab")
		)
		(pad "1" smd rect
			(at 0.2667 0 90)
			(size 0.3048 0.381)
			(layers "B.Cu" "B.Mask" "B.Paste")
			(net "P1V25_PEX1")
		)
		(pad "2" smd rect
			(at -0.2667 0 90)
			(size 0.3048 0.381)
			(layers "B.Cu" "B.Mask" "B.Paste")
			(net "GND")
		)
	)
	(footprint ""
		(layer "B.Cu")
		(at 213.70671 -225.42246 180)
		(property "Reference" "R4872"
			(at 0 0 0)
			(layer "B.SilkS")
			(hide yes)
			(effects
				(font
					(size 1.27 1.27)
				)
				(justify mirror)
			)
		)
		(property "Value" ""
			(at 0 0 0)
			(layer "B.Fab")
			(effects
				(font
					(size 1.27 1.27)
				)
				(justify mirror)
			)
		)
		(duplicate_pad_numbers_are_jumpers no)
		(fp_line
			(start 0.7874 0.4064)
			(end 0.7874 -0.4064)
			(stroke
				(width 0.1524)
				(type default)
			)
			(layer "B.SilkS")
		)
		(fp_line
			(start 0.7874 -0.4064)
			(end -0.7874 -0.4064)
			(stroke
				(width 0.1524)
				(type default)
			)
			(layer "B.SilkS")
		)
		(fp_line
			(start -0.7874 0.4064)
			(end 0.7874 0.4064)
			(stroke
				(width 0.1524)
				(type default)
			)
			(layer "B.SilkS")
		)
		(fp_line
			(start -0.7874 -0.4064)
			(end -0.7874 0.4064)
			(stroke
				(width 0.1524)
				(type default)
			)
			(layer "B.SilkS")
		)
		(fp_line
			(start 0.67945 0.3048)
			(end 0.67945 -0.305054)
			(stroke
				(width 0.1)
				(type default)
			)
			(layer "B.Fab")
		)
		(fp_line
			(start 0.67945 -0.305054)
			(end 0.12065 -0.305054)
			(stroke
				(width 0.1)
				(type default)
			)
			(layer "B.Fab")
		)
		(fp_line
			(start 0.12065 0.3048)
			(end 0.67945 0.3048)
			(stroke
				(width 0.1)
				(type default)
			)
			(layer "B.Fab")
		)
		(fp_line
			(start 0.12065 0.2794)
			(end 0.12065 0.3048)
			(stroke
				(width 0.1)
				(type default)
			)
			(layer "B.Fab")
		)
		(fp_line
			(start 0.12065 -0.2794)
			(end -0.12065 -0.2794)
			(stroke
				(width 0.1)
				(type default)
			)
			(layer "B.Fab")
		)
		(fp_line
			(start 0.12065 -0.305054)
			(end 0.12065 -0.2794)
			(stroke
				(width 0.1)
				(type default)
			)
			(layer "B.Fab")
		)
		(fp_line
			(start -0.120396 0.3048)
			(end -0.120396 0.2794)
			(stroke
				(width 0.1)
				(type default)
			)
			(layer "B.Fab")
		)
		(fp_line
			(start -0.120396 0.2794)
			(end 0.12065 0.2794)
			(stroke
				(width 0.1)
				(type default)
			)
			(layer "B.Fab")
		)
		(fp_line
			(start -0.12065 -0.2794)
			(end -0.12065 -0.3048)
			(stroke
				(width 0.1)
				(type default)
			)
			(layer "B.Fab")
		)
		(fp_line
			(start -0.12065 -0.3048)
			(end -0.67945 -0.3048)
			(stroke
				(width 0.1)
				(type default)
			)
			(layer "B.Fab")
		)
		(fp_line
			(start -0.67945 0.3048)
			(end -0.120396 0.3048)
			(stroke
				(width 0.1)
				(type default)
			)
			(layer "B.Fab")
		)
		(fp_line
			(start -0.67945 -0.3048)
			(end -0.67945 0.3048)
			(stroke
				(width 0.1)
				(type default)
			)
			(layer "B.Fab")
		)
		(pad "1" smd circle
			(at 0.40005 0)
			(size 0 0)
			(layers "B.Cu" "B.Mask" "B.Paste")
			(net "P3V3_AUX")
		)
		(pad "2" smd circle
			(at -0.40005 0)
			(size 0 0)
			(layers "B.Cu" "B.Mask" "B.Paste")
			(net "SMB_FIO_SDA")
		)
	)
)
